(kicad_pcb
	(version 20260206)
	(generator "pcbnew")
	(generator_version "10.0")
	(general
		(thickness 1.6)
		(legacy_teardrops no)
	)
	(paper "A4")
	(title_block
		(title "03242023_DA0F0TMBIJ0_F0T_Motherboard_J_brd_V01_OCP.brd")
		(comment 1 "Grand Teton / footprint 885 of 6105 (J5), pads 113-224 of 291")
	)
	(layers
		(0 "F.Cu" signal "TOP")
		(4 "In1.Cu" signal "GND")
		(6 "In2.Cu" signal "IN1")
		(8 "In3.Cu" signal "GND1")
		(10 "In4.Cu" signal "IN2")
		(12 "In5.Cu" signal "GND2")
		(14 "In6.Cu" signal "IN3")
		(16 "In7.Cu" signal "GND3")
		(18 "In8.Cu" signal "VCC")
		(20 "In9.Cu" signal "VCC1")
		(22 "In10.Cu" signal "GND4")
		(24 "In11.Cu" signal "IN4")
		(26 "In12.Cu" signal "GND5")
		(28 "In13.Cu" signal "IN5")
		(30 "In14.Cu" signal "GND6")
		(32 "In15.Cu" signal "IN6")
		(34 "In16.Cu" signal "GND7")
		(2 "B.Cu" signal "BOTTOM")
		(9 "F.Adhes" user "F.Adhesive")
		(11 "B.Adhes" user "B.Adhesive")
		(13 "F.Paste" user "Package Geometry/Pastemask Top")
		(15 "B.Paste" user "Package Geometry/Pastemask Bottom")
		(5 "F.SilkS" user "Ref Des/Silkscreen Top")
		(7 "B.SilkS" user "Ref Des/Silkscreen Bottom")
		(1 "F.Mask" user "Board Geometry/Soldermask Top")
		(3 "B.Mask" user "Board Geometry/Soldermask Bottom")
		(17 "Dwgs.User" user "User.Drawings")
		(19 "Cmts.User" user "User.Comments")
		(21 "Eco1.User" user "User.Eco1")
		(23 "Eco2.User" user "User.Eco2")
		(25 "Edge.Cuts" user "Board Geometry/Outline")
		(27 "Margin" user)
		(31 "F.CrtYd" user "Package Geometry/Place Bound Top")
		(29 "B.CrtYd" user "Package Geometry/Place Bound Bottom")
		(35 "F.Fab" user "Ref Des/Assembly Top")
		(33 "B.Fab" user "Ref Des/Assembly Bottom")
	)
	(footprint ""
		(layer "F.Cu")
		(at 273.218148 -258.091686)
		(property "Reference" "J5"
			(at -3.683 -81.702148 0)
			(unlocked yes)
			(layer "F.SilkS")
			(effects
				(font
					(size 0.7874 0.5842)
					(thickness 0.1524)
				)
				(justify left)
			)
		)
		(property "Value" ""
			(at 0 0 0)
			(layer "F.Fab")
			(effects
				(font
					(size 1.27 1.27)
				)
			)
		)
		(duplicate_pad_numbers_are_jumpers no)
		(pad "113" smd rect
			(at -2.050034 36.975034 270)
			(size 0.519938 1.4986)
			(layers "F.Cu" "F.Mask" "F.Paste")
			(net "M_C_CPU0_SB_DQ<9>")
		)
		(pad "114" smd rect
			(at -2.050034 37.824918 270)
			(size 0.519938 1.4986)
			(layers "F.Cu" "F.Mask" "F.Paste")
			(net "GND")
		)
		(pad "115" smd rect
			(at -2.050034 38.675056 270)
			(size 0.519938 1.4986)
			(layers "F.Cu" "F.Mask" "F.Paste")
			(net "M_C_CPU0_SB_DQS_DP<1>")
		)
		(pad "116" smd rect
			(at -2.050034 39.52494 270)
			(size 0.519938 1.4986)
			(layers "F.Cu" "F.Mask" "F.Paste")
			(net "M_C_CPU0_SB_DQS_DN<1>")
		)
		(pad "117" smd rect
			(at -2.050034 40.375078 270)
			(size 0.519938 1.4986)
			(layers "F.Cu" "F.Mask" "F.Paste")
			(net "GND")
		)
		(pad "118" smd rect
			(at -2.050034 41.224962 270)
			(size 0.519938 1.4986)
			(layers "F.Cu" "F.Mask" "F.Paste")
			(net "M_C_CPU0_SB_DQ<12>")
		)
		(pad "119" smd rect
			(at -2.050034 42.0751 270)
			(size 0.519938 1.4986)
			(layers "F.Cu" "F.Mask" "F.Paste")
			(net "GND")
		)
		(pad "120" smd rect
			(at -2.050034 42.924984 270)
			(size 0.519938 1.4986)
			(layers "F.Cu" "F.Mask" "F.Paste")
			(net "M_C_CPU0_SB_DQ<13>")
		)
		(pad "121" smd rect
			(at -2.050034 43.775122 270)
			(size 0.519938 1.4986)
			(layers "F.Cu" "F.Mask" "F.Paste")
			(net "GND")
		)
		(pad "122" smd rect
			(at -2.050034 44.625006 270)
			(size 0.519938 1.4986)
			(layers "F.Cu" "F.Mask" "F.Paste")
			(net "M_C_CPU0_SB_DQ<16>")
		)
		(pad "123" smd rect
			(at -2.050034 45.47489 270)
			(size 0.519938 1.4986)
			(layers "F.Cu" "F.Mask" "F.Paste")
			(net "GND")
		)
		(pad "124" smd rect
			(at -2.050034 46.325028 270)
			(size 0.519938 1.4986)
			(layers "F.Cu" "F.Mask" "F.Paste")
			(net "M_C_CPU0_SB_DQ<17>")
		)
		(pad "125" smd rect
			(at -2.050034 47.174912 270)
			(size 0.519938 1.4986)
			(layers "F.Cu" "F.Mask" "F.Paste")
			(net "GND")
		)
		(pad "126" smd rect
			(at -2.050034 48.02505 270)
			(size 0.519938 1.4986)
			(layers "F.Cu" "F.Mask" "F.Paste")
			(net "M_C_CPU0_SB_DQS_DP<2>")
		)
		(pad "127" smd rect
			(at -2.050034 48.874934 270)
			(size 0.519938 1.4986)
			(layers "F.Cu" "F.Mask" "F.Paste")
			(net "M_C_CPU0_SB_DQS_DN<2>")
		)
		(pad "128" smd rect
			(at -2.050034 49.725072 270)
			(size 0.519938 1.4986)
			(layers "F.Cu" "F.Mask" "F.Paste")
			(net "GND")
		)
		(pad "129" smd rect
			(at -2.050034 50.574956 270)
			(size 0.519938 1.4986)
			(layers "F.Cu" "F.Mask" "F.Paste")
			(net "M_C_CPU0_SB_DQ<20>")
		)
		(pad "130" smd rect
			(at -2.050034 51.425094 270)
			(size 0.519938 1.4986)
			(layers "F.Cu" "F.Mask" "F.Paste")
			(net "GND")
		)
		(pad "131" smd rect
			(at -2.050034 52.274978 270)
			(size 0.519938 1.4986)
			(layers "F.Cu" "F.Mask" "F.Paste")
			(net "M_C_CPU0_SB_DQ<21>")
		)
		(pad "132" smd rect
			(at -2.050034 53.125116 270)
			(size 0.519938 1.4986)
			(layers "F.Cu" "F.Mask" "F.Paste")
			(net "GND")
		)
		(pad "133" smd rect
			(at -2.050034 53.975 270)
			(size 0.519938 1.4986)
			(layers "F.Cu" "F.Mask" "F.Paste")
			(net "M_C_CPU0_SB_DQ<24>")
		)
		(pad "134" smd rect
			(at -2.050034 54.824884 270)
			(size 0.519938 1.4986)
			(layers "F.Cu" "F.Mask" "F.Paste")
			(net "GND")
		)
		(pad "135" smd rect
			(at -2.050034 55.675022 270)
			(size 0.519938 1.4986)
			(layers "F.Cu" "F.Mask" "F.Paste")
			(net "M_C_CPU0_SB_DQ<25>")
		)
		(pad "136" smd rect
			(at -2.050034 56.524906 270)
			(size 0.519938 1.4986)
			(layers "F.Cu" "F.Mask" "F.Paste")
			(net "GND")
		)
		(pad "137" smd rect
			(at -2.050034 57.375044 270)
			(size 0.519938 1.4986)
			(layers "F.Cu" "F.Mask" "F.Paste")
			(net "M_C_CPU0_SB_DQS_DP<3>")
		)
		(pad "138" smd rect
			(at -2.050034 58.224928 270)
			(size 0.519938 1.4986)
			(layers "F.Cu" "F.Mask" "F.Paste")
			(net "M_C_CPU0_SB_DQS_DN<3>")
		)
		(pad "139" smd rect
			(at -2.050034 59.075066 270)
			(size 0.519938 1.4986)
			(layers "F.Cu" "F.Mask" "F.Paste")
			(net "GND")
		)
		(pad "140" smd rect
			(at -2.050034 59.92495 270)
			(size 0.519938 1.4986)
			(layers "F.Cu" "F.Mask" "F.Paste")
			(net "M_C_CPU0_SB_DQ<28>")
		)
		(pad "141" smd rect
			(at -2.050034 60.775088 270)
			(size 0.519938 1.4986)
			(layers "F.Cu" "F.Mask" "F.Paste")
			(net "GND")
		)
		(pad "142" smd rect
			(at -2.050034 61.624972 270)
			(size 0.519938 1.4986)
			(layers "F.Cu" "F.Mask" "F.Paste")
			(net "M_C_CPU0_SB_DQ<29>")
		)
		(pad "143" smd rect
			(at -2.050034 62.47511 270)
			(size 0.519938 1.4986)
			(layers "F.Cu" "F.Mask" "F.Paste")
			(net "GND")
		)
		(pad "144" smd rect
			(at -2.050034 63.324994 270)
			(size 0.519938 1.4986)
			(layers "F.Cu" "F.Mask" "F.Paste")
			(net "TP_CHC_CPU0_DIMM1_FRU_1")
		)
		(pad "145" smd rect
			(at 2.050034 -63.324994 270)
			(size 0.519938 1.4986)
			(layers "F.Cu" "F.Mask" "F.Paste")
			(net "P12V_S3_AUX_CPU0_NVDIMM")
		)
		(pad "146" smd rect
			(at 2.050034 -62.47511 270)
			(size 0.519938 1.4986)
			(layers "F.Cu" "F.Mask" "F.Paste")
			(net "P12V_S3_AUX_CPU0_NVDIMM")
		)
		(pad "147" smd rect
			(at 2.050034 -61.624972 270)
			(size 0.519938 1.4986)
			(layers "F.Cu" "F.Mask" "F.Paste")
			(net "PWRGD_CHC_CPU0_DIMM1")
		)
		(pad "148" smd rect
			(at 2.050034 -60.775088 270)
			(size 0.519938 1.4986)
			(layers "F.Cu" "F.Mask" "F.Paste")
			(net "PD_CHC_CPU0_DIMM1_SAA")
		)
		(pad "149" smd rect
			(at 2.050034 -59.92495 270)
			(size 0.519938 1.4986)
			(layers "F.Cu" "F.Mask" "F.Paste")
			(net "TP_CHC_CPU0_DIMM1_FRU_2")
		)
		(pad "150" smd rect
			(at 2.050034 -59.075066 270)
			(size 0.519938 1.4986)
			(layers "F.Cu" "F.Mask" "F.Paste")
			(net "TP_CHC_CPU0_DIMM1_FRU_3")
		)
		(pad "151" smd rect
			(at 2.050034 -58.224928 270)
			(size 0.519938 1.4986)
			(layers "F.Cu" "F.Mask" "F.Paste")
			(net "GND")
		)
		(pad "152" smd rect
			(at 2.050034 -57.375044 270)
			(size 0.519938 1.4986)
			(layers "F.Cu" "F.Mask" "F.Paste")
			(net "M_C_CPU0_SA_DQ<2>")
		)
		(pad "153" smd rect
			(at 2.050034 -56.524906 270)
			(size 0.519938 1.4986)
			(layers "F.Cu" "F.Mask" "F.Paste")
			(net "GND")
		)
		(pad "154" smd rect
			(at 2.050034 -55.675022 270)
			(size 0.519938 1.4986)
			(layers "F.Cu" "F.Mask" "F.Paste")
			(net "M_C_CPU0_SA_DQ<3>")
		)
		(pad "155" smd rect
			(at 2.050034 -54.824884 270)
			(size 0.519938 1.4986)
			(layers "F.Cu" "F.Mask" "F.Paste")
			(net "GND")
		)
		(pad "156" smd rect
			(at 2.050034 -53.975 270)
			(size 0.519938 1.4986)
			(layers "F.Cu" "F.Mask" "F.Paste")
			(net "M_C_CPU0_SA_DQS_DN<5>")
		)
		(pad "157" smd rect
			(at 2.050034 -53.125116 270)
			(size 0.519938 1.4986)
			(layers "F.Cu" "F.Mask" "F.Paste")
			(net "M_C_CPU0_SA_DQS_DP<5>")
		)
		(pad "158" smd rect
			(at 2.050034 -52.274978 270)
			(size 0.519938 1.4986)
			(layers "F.Cu" "F.Mask" "F.Paste")
			(net "GND")
		)
		(pad "159" smd rect
			(at 2.050034 -51.425094 270)
			(size 0.519938 1.4986)
			(layers "F.Cu" "F.Mask" "F.Paste")
			(net "M_C_CPU0_SA_DQ<6>")
		)
		(pad "160" smd rect
			(at 2.050034 -50.574956 270)
			(size 0.519938 1.4986)
			(layers "F.Cu" "F.Mask" "F.Paste")
			(net "GND")
		)
		(pad "161" smd rect
			(at 2.050034 -49.725072 270)
			(size 0.519938 1.4986)
			(layers "F.Cu" "F.Mask" "F.Paste")
			(net "M_C_CPU0_SA_DQ<7>")
		)
		(pad "162" smd rect
			(at 2.050034 -48.874934 270)
			(size 0.519938 1.4986)
			(layers "F.Cu" "F.Mask" "F.Paste")
			(net "GND")
		)
		(pad "163" smd rect
			(at 2.050034 -48.02505 270)
			(size 0.519938 1.4986)
			(layers "F.Cu" "F.Mask" "F.Paste")
			(net "M_C_CPU0_SA_DQ<10>")
		)
		(pad "164" smd rect
			(at 2.050034 -47.174912 270)
			(size 0.519938 1.4986)
			(layers "F.Cu" "F.Mask" "F.Paste")
			(net "GND")
		)
		(pad "165" smd rect
			(at 2.050034 -46.325028 270)
			(size 0.519938 1.4986)
			(layers "F.Cu" "F.Mask" "F.Paste")
			(net "M_C_CPU0_SA_DQ<11>")
		)
		(pad "166" smd rect
			(at 2.050034 -45.47489 270)
			(size 0.519938 1.4986)
			(layers "F.Cu" "F.Mask" "F.Paste")
			(net "GND")
		)
		(pad "167" smd rect
			(at 2.050034 -44.625006 270)
			(size 0.519938 1.4986)
			(layers "F.Cu" "F.Mask" "F.Paste")
			(net "M_C_CPU0_SA_DQS_DN<6>")
		)
		(pad "168" smd rect
			(at 2.050034 -43.775122 270)
			(size 0.519938 1.4986)
			(layers "F.Cu" "F.Mask" "F.Paste")
			(net "M_C_CPU0_SA_DQS_DP<6>")
		)
		(pad "169" smd rect
			(at 2.050034 -42.924984 270)
			(size 0.519938 1.4986)
			(layers "F.Cu" "F.Mask" "F.Paste")
			(net "GND")
		)
		(pad "170" smd rect
			(at 2.050034 -42.0751 270)
			(size 0.519938 1.4986)
			(layers "F.Cu" "F.Mask" "F.Paste")
			(net "M_C_CPU0_SA_DQ<14>")
		)
		(pad "171" smd rect
			(at 2.050034 -41.224962 270)
			(size 0.519938 1.4986)
			(layers "F.Cu" "F.Mask" "F.Paste")
			(net "GND")
		)
		(pad "172" smd rect
			(at 2.050034 -40.375078 270)
			(size 0.519938 1.4986)
			(layers "F.Cu" "F.Mask" "F.Paste")
			(net "M_C_CPU0_SA_DQ<15>")
		)
		(pad "173" smd rect
			(at 2.050034 -39.52494 270)
			(size 0.519938 1.4986)
			(layers "F.Cu" "F.Mask" "F.Paste")
			(net "GND")
		)
		(pad "174" smd rect
			(at 2.050034 -38.675056 270)
			(size 0.519938 1.4986)
			(layers "F.Cu" "F.Mask" "F.Paste")
			(net "M_C_CPU0_SA_DQ<18>")
		)
		(pad "175" smd rect
			(at 2.050034 -37.824918 270)
			(size 0.519938 1.4986)
			(layers "F.Cu" "F.Mask" "F.Paste")
			(net "GND")
		)
		(pad "176" smd rect
			(at 2.050034 -36.975034 270)
			(size 0.519938 1.4986)
			(layers "F.Cu" "F.Mask" "F.Paste")
			(net "M_C_CPU0_SA_DQ<19>")
		)
		(pad "177" smd rect
			(at 2.050034 -36.124896 270)
			(size 0.519938 1.4986)
			(layers "F.Cu" "F.Mask" "F.Paste")
			(net "GND")
		)
		(pad "178" smd rect
			(at 2.050034 -35.275012 270)
			(size 0.519938 1.4986)
			(layers "F.Cu" "F.Mask" "F.Paste")
			(net "M_C_CPU0_SA_DQS_DN<7>")
		)
		(pad "179" smd rect
			(at 2.050034 -34.425128 270)
			(size 0.519938 1.4986)
			(layers "F.Cu" "F.Mask" "F.Paste")
			(net "M_C_CPU0_SA_DQS_DP<7>")
		)
		(pad "180" smd rect
			(at 2.050034 -33.57499 270)
			(size 0.519938 1.4986)
			(layers "F.Cu" "F.Mask" "F.Paste")
			(net "GND")
		)
		(pad "181" smd rect
			(at 2.050034 -32.725106 270)
			(size 0.519938 1.4986)
			(layers "F.Cu" "F.Mask" "F.Paste")
			(net "M_C_CPU0_SA_DQ<22>")
		)
		(pad "182" smd rect
			(at 2.050034 -31.874968 270)
			(size 0.519938 1.4986)
			(layers "F.Cu" "F.Mask" "F.Paste")
			(net "GND")
		)
		(pad "183" smd rect
			(at 2.050034 -31.025084 270)
			(size 0.519938 1.4986)
			(layers "F.Cu" "F.Mask" "F.Paste")
			(net "M_C_CPU0_SA_DQ<23>")
		)
		(pad "184" smd rect
			(at 2.050034 -30.174946 270)
			(size 0.519938 1.4986)
			(layers "F.Cu" "F.Mask" "F.Paste")
			(net "GND")
		)
		(pad "185" smd rect
			(at 2.050034 -29.325062 270)
			(size 0.519938 1.4986)
			(layers "F.Cu" "F.Mask" "F.Paste")
			(net "M_C_CPU0_SA_DQ<26>")
		)
		(pad "186" smd rect
			(at 2.050034 -28.474924 270)
			(size 0.519938 1.4986)
			(layers "F.Cu" "F.Mask" "F.Paste")
			(net "GND")
		)
		(pad "187" smd rect
			(at 2.050034 -27.62504 270)
			(size 0.519938 1.4986)
			(layers "F.Cu" "F.Mask" "F.Paste")
			(net "M_C_CPU0_SA_DQ<27>")
		)
		(pad "188" smd rect
			(at 2.050034 -26.774902 270)
			(size 0.519938 1.4986)
			(layers "F.Cu" "F.Mask" "F.Paste")
			(net "GND")
		)
		(pad "189" smd rect
			(at 2.050034 -25.925018 270)
			(size 0.519938 1.4986)
			(layers "F.Cu" "F.Mask" "F.Paste")
			(net "M_C_CPU0_SA_DQS_DN<8>")
		)
		(pad "190" smd rect
			(at 2.050034 -25.07488 270)
			(size 0.519938 1.4986)
			(layers "F.Cu" "F.Mask" "F.Paste")
			(net "M_C_CPU0_SA_DQS_DP<8>")
		)
		(pad "191" smd rect
			(at 2.050034 -24.224996 270)
			(size 0.519938 1.4986)
			(layers "F.Cu" "F.Mask" "F.Paste")
			(net "GND")
		)
		(pad "192" smd rect
			(at 2.050034 -23.375112 270)
			(size 0.519938 1.4986)
			(layers "F.Cu" "F.Mask" "F.Paste")
			(net "M_C_CPU0_SA_DQ<30>")
		)
		(pad "193" smd rect
			(at 2.050034 -22.524974 270)
			(size 0.519938 1.4986)
			(layers "F.Cu" "F.Mask" "F.Paste")
			(net "GND")
		)
		(pad "194" smd rect
			(at 2.050034 -21.67509 270)
			(size 0.519938 1.4986)
			(layers "F.Cu" "F.Mask" "F.Paste")
			(net "M_C_CPU0_SA_DQ<31>")
		)
		(pad "195" smd rect
			(at 2.050034 -20.824952 270)
			(size 0.519938 1.4986)
			(layers "F.Cu" "F.Mask" "F.Paste")
			(net "GND")
		)
		(pad "196" smd rect
			(at 2.050034 -19.975068 270)
			(size 0.519938 1.4986)
			(layers "F.Cu" "F.Mask" "F.Paste")
			(net "M_C_CPU0_SA_CB<2>")
		)
		(pad "197" smd rect
			(at 2.050034 -19.12493 270)
			(size 0.519938 1.4986)
			(layers "F.Cu" "F.Mask" "F.Paste")
			(net "GND")
		)
		(pad "198" smd rect
			(at 2.050034 -18.275046 270)
			(size 0.519938 1.4986)
			(layers "F.Cu" "F.Mask" "F.Paste")
			(net "M_C_CPU0_SA_CB<3>")
		)
		(pad "199" smd rect
			(at 2.050034 -17.424908 270)
			(size 0.519938 1.4986)
			(layers "F.Cu" "F.Mask" "F.Paste")
			(net "GND")
		)
		(pad "200" smd rect
			(at 2.050034 -16.575024 270)
			(size 0.519938 1.4986)
			(layers "F.Cu" "F.Mask" "F.Paste")
			(net "M_C_CPU0_SA_DQS_DN<9>")
		)
		(pad "201" smd rect
			(at 2.050034 -15.724886 270)
			(size 0.519938 1.4986)
			(layers "F.Cu" "F.Mask" "F.Paste")
			(net "M_C_CPU0_SA_DQS_DP<9>")
		)
		(pad "202" smd rect
			(at 2.050034 -14.875002 270)
			(size 0.519938 1.4986)
			(layers "F.Cu" "F.Mask" "F.Paste")
			(net "GND")
		)
		(pad "203" smd rect
			(at 2.050034 -14.025118 270)
			(size 0.519938 1.4986)
			(layers "F.Cu" "F.Mask" "F.Paste")
			(net "M_C_CPU0_SA_CB<6>")
		)
		(pad "204" smd rect
			(at 2.050034 -13.17498 270)
			(size 0.519938 1.4986)
			(layers "F.Cu" "F.Mask" "F.Paste")
			(net "GND")
		)
		(pad "205" smd rect
			(at 2.050034 -12.325096 270)
			(size 0.519938 1.4986)
			(layers "F.Cu" "F.Mask" "F.Paste")
			(net "M_C_CPU0_SA_CB<7>")
		)
		(pad "206" smd rect
			(at 2.050034 -11.474958 270)
			(size 0.519938 1.4986)
			(layers "F.Cu" "F.Mask" "F.Paste")
			(net "GND")
		)
		(pad "207" smd rect
			(at 2.050034 -10.625074 270)
			(size 0.519938 1.4986)
			(layers "F.Cu" "F.Mask" "F.Paste")
			(net "RST_M_CD_CPU0_FPGA_N")
		)
		(pad "208" smd rect
			(at 2.050034 -9.774936 270)
			(size 0.519938 1.4986)
			(layers "F.Cu" "F.Mask" "F.Paste")
			(net "GND")
		)
		(pad "209" smd rect
			(at 2.050034 -8.925052 270)
			(size 0.519938 1.4986)
			(layers "F.Cu" "F.Mask" "F.Paste")
			(net "M_C_CPU0_SA_CS_N<1>")
		)
		(pad "210" smd rect
			(at 2.050034 -8.074914 270)
			(size 0.519938 1.4986)
			(layers "F.Cu" "F.Mask" "F.Paste")
			(net "GND")
		)
		(pad "211" smd rect
			(at 2.050034 -7.22503 270)
			(size 0.519938 1.4986)
			(layers "F.Cu" "F.Mask" "F.Paste")
			(net "M_C_CPU0_SA_CA<1>")
		)
		(pad "212" smd rect
			(at 2.050034 -6.374892 270)
			(size 0.519938 1.4986)
			(layers "F.Cu" "F.Mask" "F.Paste")
			(net "GND")
		)
		(pad "213" smd rect
			(at 2.050034 -5.525008 270)
			(size 0.519938 1.4986)
			(layers "F.Cu" "F.Mask" "F.Paste")
			(net "M_C_CPU0_SA_CA<3>")
		)
		(pad "214" smd rect
			(at 2.050034 -4.675124 270)
			(size 0.519938 1.4986)
			(layers "F.Cu" "F.Mask" "F.Paste")
			(net "GND")
		)
		(pad "215" smd rect
			(at 2.050034 -3.824986 270)
			(size 0.519938 1.4986)
			(layers "F.Cu" "F.Mask" "F.Paste")
			(net "M_C_CPU0_SA_CA<5>")
		)
		(pad "216" smd rect
			(at 2.050034 -2.975102 270)
			(size 0.519938 1.4986)
			(layers "F.Cu" "F.Mask" "F.Paste")
			(net "GND")
		)
		(pad "217" smd rect
			(at 2.050034 -2.124964 270)
			(size 0.519938 1.4986)
			(layers "F.Cu" "F.Mask" "F.Paste")
			(net "M_C_CPU0_CLK_DP<0>")
		)
		(pad "218" smd rect
			(at 2.050034 -1.27508 270)
			(size 0.519938 1.4986)
			(layers "F.Cu" "F.Mask" "F.Paste")
			(net "M_C_CPU0_CLK_DN<0>")
		)
		(pad "219" smd rect
			(at 2.050034 -0.424942 270)
			(size 0.519938 1.4986)
			(layers "F.Cu" "F.Mask" "F.Paste")
			(net "GND")
		)
		(pad "220" smd rect
			(at 2.050034 5.525008 270)
			(size 0.519938 1.4986)
			(layers "F.Cu" "F.Mask" "F.Paste")
			(net "TP_CHC_CPU0_DIMM1_FRU_4")
		)
		(pad "221" smd rect
			(at 2.050034 6.374892 270)
			(size 0.519938 1.4986)
			(layers "F.Cu" "F.Mask" "F.Paste")
			(net "M_C_CPU0_SB_CA<1>")
		)
		(pad "222" smd rect
			(at 2.050034 7.22503 270)
			(size 0.519938 1.4986)
			(layers "F.Cu" "F.Mask" "F.Paste")
			(net "GND")
		)
		(pad "223" smd rect
			(at 2.050034 8.074914 270)
			(size 0.519938 1.4986)
			(layers "F.Cu" "F.Mask" "F.Paste")
			(net "M_C_CPU0_SB_CA<3>")
		)
		(pad "224" smd rect
			(at 2.050034 8.925052 270)
			(size 0.519938 1.4986)
			(layers "F.Cu" "F.Mask" "F.Paste")
			(net "GND")
		)
	)
)
